# T6G (Grand Teton) — schematic netlist excerpt (pin names and nets, part order shuffled) for the footprints in the layout excerpt that follows; sources: Cadence DE-HDL packaged netlist, KiCad conversion of 04192023_DAF0TMB3IC0_F0TG_MB_C_brd_V02_OCP.brd

R3972  Q_RES  0 5% CHIP  pkg 0402LF  page 146 : A = P12V_E1S_PWRGD_0 ; B = HP_LVC3_E1S_0_HSC_PWRGD
PC6577_2  Q_CAP  1UF 25V 10% X6S  pkg C0402  page 363 : A = SW_P12V_AUX_P0V9_RETIMER_CPU0_FLT ; B = GND

(kicad_pcb
	(version 20260206)
	(generator "pcbnew")
	(generator_version "10.0")
	(general
		(thickness 1.6)
		(legacy_teardrops no)
	)
	(paper "A4")
	(title_block
		(title "04192023_DAF0TMB3IC0_F0TG_MB_C_brd_V02_OCP.brd")
		(comment 1 "Grand Teton / footprints 4275-4276 of 8354")
	)
	(layers
		(0 "F.Cu" signal "TOP")
		(4 "In1.Cu" signal "GND")
		(6 "In2.Cu" signal "IN1")
		(8 "In3.Cu" signal "GND1")
		(10 "In4.Cu" signal "IN2")
		(12 "In5.Cu" signal "GND2")
		(14 "In6.Cu" signal "IN3")
		(16 "In7.Cu" signal "GND3")
		(18 "In8.Cu" signal "VCC")
		(20 "In9.Cu" signal "VCC1")
		(22 "In10.Cu" signal "GND4")
		(24 "In11.Cu" signal "IN4")
		(26 "In12.Cu" signal "GND5")
		(28 "In13.Cu" signal "IN5")
		(30 "In14.Cu" signal "GND6")
		(32 "In15.Cu" signal "IN6")
		(34 "In16.Cu" signal "GND7")
		(2 "B.Cu" signal "BOTTOM")
		(9 "F.Adhes" user "F.Adhesive")
		(11 "B.Adhes" user "B.Adhesive")
		(13 "F.Paste" user "Package Geometry/Pastemask Top")
		(15 "B.Paste" user "Package Geometry/Pastemask Bottom")
		(5 "F.SilkS" user "Ref Des/Silkscreen Top")
		(7 "B.SilkS" user "Ref Des/Silkscreen Bottom")
		(1 "F.Mask" user "Board Geometry/Soldermask Top")
		(3 "B.Mask" user "Board Geometry/Soldermask Bottom")
		(17 "Dwgs.User" user "User.Drawings")
		(19 "Cmts.User" user "User.Comments")
		(21 "Eco1.User" user "User.Eco1")
		(23 "Eco2.User" user "User.Eco2")
		(25 "Edge.Cuts" user "Board Geometry/Outline")
		(27 "Margin" user)
		(31 "F.CrtYd" user "Package Geometry/Place Bound Top")
		(29 "B.CrtYd" user "Package Geometry/Place Bound Bottom")
		(35 "F.Fab" user "Ref Des/Assembly Top")
		(33 "B.Fab" user "Ref Des/Assembly Bottom")
	)
	(footprint ""
		(layer "F.Cu")
		(at 457.796646 -397.322802 -90)
		(property "Reference" "PC6577_2"
			(at 0 0 270)
			(layer "F.SilkS")
			(hide yes)
			(effects
				(font
					(size 1.27 1.27)
				)
			)
		)
		(property "Value" ""
			(at 0 0 270)
			(layer "F.Fab")
			(effects
				(font
					(size 1.27 1.27)
				)
			)
		)
		(duplicate_pad_numbers_are_jumpers no)
		(fp_line
			(start -0.7874 0.4064)
			(end -0.7874 -0.4064)
			(stroke
				(width 0.1524)
				(type default)
			)
			(layer "F.SilkS")
		)
		(fp_line
			(start 0.7874 0.4064)
			(end -0.7874 0.4064)
			(stroke
				(width 0.1524)
				(type default)
			)
			(layer "F.SilkS")
		)
		(fp_line
			(start -0.7874 -0.4064)
			(end 0.7874 -0.4064)
			(stroke
				(width 0.1524)
				(type default)
			)
			(layer "F.SilkS")
		)
		(fp_line
			(start 0.7874 -0.4064)
			(end 0.7874 0.4064)
			(stroke
				(width 0.1524)
				(type default)
			)
			(layer "F.SilkS")
		)
		(fp_line
			(start -0.67945 0.3048)
			(end -0.67945 -0.305054)
			(stroke
				(width 0.1)
				(type default)
			)
			(layer "F.Fab")
		)
		(fp_line
			(start -0.12065 0.3048)
			(end -0.67945 0.3048)
			(stroke
				(width 0.1)
				(type default)
			)
			(layer "F.Fab")
		)
		(fp_line
			(start 0.120396 0.3048)
			(end 0.120396 0.2794)
			(stroke
				(width 0.1)
				(type default)
			)
			(layer "F.Fab")
		)
		(fp_line
			(start 0.67945 0.3048)
			(end 0.120396 0.3048)
			(stroke
				(width 0.1)
				(type default)
			)
			(layer "F.Fab")
		)
		(fp_line
			(start -0.12065 0.2794)
			(end -0.12065 0.3048)
			(stroke
				(width 0.1)
				(type default)
			)
			(layer "F.Fab")
		)
		(fp_line
			(start 0.120396 0.2794)
			(end -0.12065 0.2794)
			(stroke
				(width 0.1)
				(type default)
			)
			(layer "F.Fab")
		)
		(fp_line
			(start -0.12065 -0.2794)
			(end 0.12065 -0.2794)
			(stroke
				(width 0.1)
				(type default)
			)
			(layer "F.Fab")
		)
		(fp_line
			(start 0.12065 -0.2794)
			(end 0.12065 -0.3048)
			(stroke
				(width 0.1)
				(type default)
			)
			(layer "F.Fab")
		)
		(fp_line
			(start 0.12065 -0.3048)
			(end 0.67945 -0.3048)
			(stroke
				(width 0.1)
				(type default)
			)
			(layer "F.Fab")
		)
		(fp_line
			(start 0.67945 -0.3048)
			(end 0.67945 0.3048)
			(stroke
				(width 0.1)
				(type default)
			)
			(layer "F.Fab")
		)
		(fp_line
			(start -0.67945 -0.305054)
			(end -0.12065 -0.305054)
			(stroke
				(width 0.1)
				(type default)
			)
			(layer "F.Fab")
		)
		(fp_line
			(start -0.12065 -0.305054)
			(end -0.12065 -0.2794)
			(stroke
				(width 0.1)
				(type default)
			)
			(layer "F.Fab")
		)
		(pad "1" smd circle
			(at -0.40005 0 270)
			(size 0 0)
			(layers "F.Cu" "F.Mask" "F.Paste")
			(net "SW_P12V_AUX_P0V9_RETIMER_CPU0_FLT")
		)
		(pad "2" smd circle
			(at 0.40005 0 270)
			(size 0 0)
			(layers "F.Cu" "F.Mask" "F.Paste")
			(net "GND")
		)
	)
	(footprint ""
		(layer "F.Cu")
		(at 250.317 -39.064946 -90)
		(property "Reference" "R3972"
			(at 0 0 270)
			(layer "F.SilkS")
			(hide yes)
			(effects
				(font
					(size 1.27 1.27)
				)
			)
		)
		(property "Value" ""
			(at 0 0 270)
			(layer "F.Fab")
			(effects
				(font
					(size 1.27 1.27)
				)
			)
		)
		(duplicate_pad_numbers_are_jumpers no)
		(fp_line
			(start -0.7874 0.4064)
			(end -0.7874 -0.4064)
			(stroke
				(width 0.1524)
				(type default)
			)
			(layer "F.SilkS")
		)
		(fp_line
			(start 0.7874 0.4064)
			(end -0.7874 0.4064)
			(stroke
				(width 0.1524)
				(type default)
			)
			(layer "F.SilkS")
		)
		(fp_line
			(start -0.7874 -0.4064)
			(end 0.7874 -0.4064)
			(stroke
				(width 0.1524)
				(type default)
			)
			(layer "F.SilkS")
		)
		(fp_line
			(start 0.7874 -0.4064)
			(end 0.7874 0.4064)
			(stroke
				(width 0.1524)
				(type default)
			)
			(layer "F.SilkS")
		)
		(fp_line
			(start -0.67945 0.3048)
			(end -0.67945 -0.305054)
			(stroke
				(width 0.1)
				(type default)
			)
			(layer "F.Fab")
		)
		(fp_line
			(start -0.12065 0.3048)
			(end -0.67945 0.3048)
			(stroke
				(width 0.1)
				(type default)
			)
			(layer "F.Fab")
		)
		(fp_line
			(start 0.120396 0.3048)
			(end 0.120396 0.2794)
			(stroke
				(width 0.1)
				(type default)
			)
			(layer "F.Fab")
		)
		(fp_line
			(start 0.67945 0.3048)
			(end 0.120396 0.3048)
			(stroke
				(width 0.1)
				(type default)
			)
			(layer "F.Fab")
		)
		(fp_line
			(start -0.12065 0.2794)
			(end -0.12065 0.3048)
			(stroke
				(width 0.1)
				(type default)
			)
			(layer "F.Fab")
		)
		(fp_line
			(start 0.120396 0.2794)
			(end -0.12065 0.2794)
			(stroke
				(width 0.1)
				(type default)
			)
			(layer "F.Fab")
		)
		(fp_line
			(start -0.12065 -0.2794)
			(end 0.12065 -0.2794)
			(stroke
				(width 0.1)
				(type default)
			)
			(layer "F.Fab")
		)
		(fp_line
			(start 0.12065 -0.2794)
			(end 0.12065 -0.3048)
			(stroke
				(width 0.1)
				(type default)
			)
			(layer "F.Fab")
		)
		(fp_line
			(start 0.12065 -0.3048)
			(end 0.67945 -0.3048)
			(stroke
				(width 0.1)
				(type default)
			)
			(layer "F.Fab")
		)
		(fp_line
			(start 0.67945 -0.3048)
			(end 0.67945 0.3048)
			(stroke
				(width 0.1)
				(type default)
			)
			(layer "F.Fab")
		)
		(fp_line
			(start -0.67945 -0.305054)
			(end -0.12065 -0.305054)
			(stroke
				(width 0.1)
				(type default)
			)
			(layer "F.Fab")
		)
		(fp_line
			(start -0.12065 -0.305054)
			(end -0.12065 -0.2794)
			(stroke
				(width 0.1)
				(type default)
			)
			(layer "F.Fab")
		)
		(pad "1" smd circle
			(at -0.40005 0 270)
			(size 0 0)
			(layers "F.Cu" "F.Mask" "F.Paste")
			(net "P12V_E1S_PWRGD_0")
		)
		(pad "2" smd circle
			(at 0.40005 0 270)
			(size 0 0)
			(layers "F.Cu" "F.Mask" "F.Paste")
			(net "HP_LVC3_E1S_0_HSC_PWRGD")
		)
	)
)
